#ISCELL
  logical_power cad_note *
  *
#ISCELL
  mstr_misc dns *
  *
#ISCELL
  pure_quanta quanta_title_block_c *
  *
#ISCELL
  standard offpage *
  page52_i1
#ISCELL
  logical_power universal_gnd *
  page52_i100
#CELL
  pure_quanta q_cap *
  page52_i101
#CELL
  pure_quanta q_cap *
  page52_i102
#CELL
  pure_quanta mc74vhc1g32dtt1g *
  page52_i104
#ISCELL
  standard offpage *
  page52_i105
#CELL
  pure_quanta q_cap *
  page52_i107
#ISCELL
  logical_power universal_gnd *
  page52_i109
#CELL
  pure_quanta q_cap *
  page52_i11
#ISCELL
  logical_power universal_gnd *
  page52_i112
#ISCELL
  standard offpage *
  page52_i113
#CELL
  pure_quanta 74lvc1g08gw *
  page52_i114
#ISCELL
  standard offpage *
  page52_i115
#ISCELL
  logical_power universal_gnd *
  page52_i118
#CELL
  pure_quanta q_cap *
  page52_i119
#ISCELL
  logical_power universal_gnd *
  page52_i12
#ISCELL
  logical_power universal_gnd *
  page52_i120
#ISCELL
  standard offpage *
  page52_i122
#ISCELL
  logical_power universal_gnd *
  page52_i124
#CELL
  pure_quanta q_cap *
  page52_i125
#CELL
  pure_quanta q_res *
  page52_i127
#CELL
  pure_quanta q_res *
  page52_i13
#ISCELL
  standard offpage *
  page52_i130
#ISCELL
  standard offpage *
  page52_i136
#CELL
  pure_quanta q_res *
  page52_i137
#ISCELL
  standard offpage *
  page52_i138
#CELL
  pure_quanta q_res *
  page52_i139
#ISCELL
  standard offpage *
  page52_i140
#CELL
  pure_quanta q_res *
  page52_i141
#ISCELL
  standard offpage *
  page52_i142
#ISCELL
  logical_power universal_power *
  page52_i143
#ISCELL
  logical_power universal_power *
  page52_i144
#CELL
  pure_quanta q_res *
  page52_i145
#CELL
  pure_quanta q_res *
  page52_i146
#CELL
  pure_quanta q_res *
  page52_i147
#CELL
  pure_quanta q_cap *
  page52_i15
#CELL
  pure_quanta q_res *
  page52_i17
#ISCELL
  logical_power universal_gnd *
  page52_i18
#ISCELL
  logical_power vccaux15 *
  page52_i2
#CELL
  pure_quanta q_cap *
  page52_i23
#CELL
  pure_quanta q_res *
  page52_i25
#ISCELL
  logical_power universal_gnd *
  page52_i28
#ISCELL
  logical_power vccaux15 *
  page52_i31
#CELL
  pure_quanta q_inductor *
  page52_i32
#CELL
  pure_quanta q_cap *
  page52_i35
#CELL
  pure_quanta q_cap *
  page52_i36
#CELL
  pure_quanta q_cap *
  page52_i37
#CELL
  pure_quanta q_cap *
  page52_i38
#ISCELL
  logical_power universal_power *
  page52_i39
#ISCELL
  logical_power universal_gnd *
  page52_i4
#ISCELL
  logical_power universal_gnd *
  page52_i5
#ISCELL
  standard offpage *
  page52_i55
#ISCELL
  logical_power universal_gnd *
  page52_i62
#CELL
  pure_quanta q_cap *
  page52_i63
#ISCELL
  logical_power universal_gnd *
  page52_i64
#ISCELL
  logical_power vccaux15 *
  page52_i65
#CELL
  pure_quanta q_cap *
  page52_i66
#ISCELL
  logical_power universal_gnd *
  page52_i67
#ISCELL
  logical_power universal_power *
  page52_i68
#CELL
  pure_quanta q_cap *
  page52_i73
#ISCELL
  logical_power universal_gnd *
  page52_i74
#ISCELL
  standard offpage *
  page52_i75
#CELL
  pure_quanta ap22811aw57 *
  page52_i79
#CELL
  pure_quanta q_cap *
  page52_i80
#CELL
  pure_quanta q_cap *
  page52_i81
#CELL
  pure_quanta mpq8626gdz *
  page52_i82
#ISCELL
  logical_power universal_gnd *
  page52_i84
#ISCELL
  logical_power universal_gnd *
  page52_i85
#CELL
  pure_quanta q_cap *
  page52_i86
#CELL
  pure_quanta q_res *
  page52_i87
#CELL
  pure_quanta q_res *
  page52_i88
#ISCELL
  logical_power universal_gnd *
  page52_i89
#CELL
  pure_quanta q_cap *
  page52_i9
#CELL
  pure_quanta q_cap *
  page52_i91
#CELL
  pure_quanta q_inductor *
  page52_i92
#CELL
  pure_quanta q_cap *
  page52_i93
#ISCELL
  logical_power universal_gnd *
  page52_i94
#CELL
  pure_quanta q_res *
  page52_i95
#CELL
  pure_quanta q_res *
  page52_i96
#CELL
  pure_quanta q_res *
  page52_i97
#ISCELL
  standard offpage *
  page52_i99
